FILE_TYPE = CONNECTIVITY;
{Allegro Design Entry HDL 16.6-p007 (v16-6-112F) 10/10/2012}
"PAGE_NUMBER" = 246;
0"NC";
1"GND\g";
2"GND\g";
3"P3V3_STBY\g";
4"GND\g";
5"TP_TPM_SPI_3";
6"SPI_BMC_BT_DO";
7"SPI_BMC_BT_CLK";
8"SPI_BMC_BT_CS0_N";
9"PU_TPM_SPI_FLASH_RESET_2_N";
10"TP_TPM_SPI_6";
11"TP_TPM_SPI_4";
12"TP_TPM_SPI_5";
13"PU_TPM_SPI_BMC_HOLD_N";
14"SPI_BMC_BT_DI";
15"TP_TPM_SPI_2";
16"TP_TPM_SPI_1";
17"TP_TPM_SPI_0";
18"SPI_TPM_BMC_DI_R";
19"TPM_SPI_BMC_WP_N";
%"RES"
"2","(-5775,3200)","2","mstr_discrete","I11";
;
PART_NUMBER"G21796-072"
WATTAGE"1/16W"
PACK_TYPE"0402"
TOLERANCE"1%"
VALUE"4.75K"
LOCATION"RN8F3"
MATERIAL"CHIP"
CDS_LOCATION"RN8F3"
CDS_SEC"1"
CDS_LIB"mstr_discrete"
BOM_COST"SM_MEM"
SEC_TYPE"0402"
ROOM"BMC_BOOT_SPI"
SEC"1";
"A"
$PN"1"3;
"B"
$PN"2"13;
%"RES"
"2","(-5225,3225)","2","mstr_discrete","I12";
;
PACK_TYPE"0402"
WATTAGE"1/16W"
VALUE"4.75K"
MATERIAL"EMPTY"
TOLERANCE"1%"
LOCATION"RN8F4"
PART_NUMBER"G21796-072"
CDS_SEC"1"
CDS_LIB"mstr_discrete"
CDS_LOCATION"RN8F4"
SEC_TYPE"0402"
SEC"1"
BOM_COST"SM_MEM"
ROOM"BMC_BOOT_SPI";
"A"
$PN"1"3;
"B"
$PN"2"9;
%"GND"
"1","(-3025,2300)","0","mstr_symbols","I13";
;
CDS_LIB"mstr_symbols"
SIZE"1B"
VOLTAGE"0"
BODY_TYPE"PLUMBING"
HDL_POWER"GND";
"A\NAC"1;
%"GND"
"1","(-2700,2950)","0","mstr_symbols","I14";
;
SIZE"1B"
CDS_LIB"mstr_symbols"
VOLTAGE"0.0V"
BODY_TYPE"PLUMBING"
HDL_POWER"GND";
"A\NAC"2;
%"W25Q256"
"1","(-3675,2750)","0","mstr_memory","I17";
;
MATERIAL"IC"
PART_NUMBER"H25002-001"
LOCATION"UN8F2"
SEC"1"
BOM_COST"SM_MEM"
SEC_TYPE"XSOI"
ROOM"BMC_BOOT_SPI"
PACK_TYPE"XSOI"
CDS_LIB"mstr_memory"
CDS_LOCATION"UN8F2"
CDS_SEC"1";
"HOLD_N_IO<3>"
$PN"1"13;
"RESET_N"
$PN"3"9;
"DI_IO<0>"
$PN"15"6;
"CS_N"
$PN"7"8;
"VCC"
$PN"2"3;
"CLK"
$PN"16"7;
"DO_IO<1>"
$PN"8"18;
"GND"
$PN"10"1;
"NC<6>"
$PN"4"10;
"NC<5>"
$PN"5"12;
"NC<4>"
$PN"6"11;
"NC<3>"
$PN"11"5;
"NC<2>"
$PN"12"15;
"NC<1>"
$PN"13"16;
"NC<0>"
$PN"14"17;
"WP_N_IO<2>"
$PN"9"19;
%"82KR2F-1-GP"
"1","(-6225,2300)","0","w_hdl","I19";
;
CDS_SEC"1"
$SEC"1"
CDS_LOCATION"RN8F6"
ATTRIBUTE"82KOHM"
TOLERANCE"1%"
VALUE"82KR2F-1-GP"
LOCATION"RN8F6"
PACK_SIZE"0402"
RATED"1/16W"
CDS_LMAN_SYM_OUTLINE"-50,75,50,-75"
CDS_LIB"w_hdl"
PART_NUMBER"64.82025.6DL"
PACK_TYPE"SMD-RG";
"2"
$PN"2"4;
"1"
$PN"1"19;
%"RES"
"2","(-6225,3225)","2","mstr_discrete","I20";
;
CDS_SEC"1"
CDS_LOCATION"RN8F2"
PART_NUMBER"G21796-072"
WATTAGE"1/16W"
PACK_TYPE"0402"
LOCATION"RN8F2"
VALUE"4.75K"
MATERIAL"EMPTY"
TOLERANCE"1%"
SEC_TYPE"0402"
SEC"1"
CDS_LIB"mstr_discrete"
ROOM"BMC_BOOT_SPI"
BOM_COST"SM_MEM";
"A"
$PN"1"3;
"B"
$PN"2"19;
%"CAP_A"
"1","(-3000,3275)","0","dev_discrete","I21";
;
LOCATION"CN8F1"
VALUE"1.0UF"
VOLTAGE"6.3V"
MATERIAL"X6S"
PACK_TYPE"0402V"
PART_NUMBER"D97712-004"
TOLERANCE"10%"
CDS_LIB"dev_discrete"
CDS_SEC"1"
SEC_TYPE"0402V"
SEC"1"
ROOM"VDDQ_KLM_PWR_VR"
CDS_LOCATION"CN8F1";
"B"
$PN"2"2;
"A"
$PN"1"3;
%"CAP_A"
"1","(-2700,3275)","2","dev_discrete","I22";
;
LOCATION"CN8F2"
VALUE"0.01UF"
VOLTAGE"25V"
TOLERANCE"10%"
MATERIAL"X7R"
PACK_TYPE"0402V"
PART_NUMBER"A36096-045"
ROOM"DDR4_CH_M"
SEC"1"
SEC_TYPE"0402V"
CDS_SEC"1"
CDS_LIB"dev_discrete"
BOM_COST"MEM"
CDS_LOCATION"CN8F2";
"B"
$PN"2"2;
"A"
$PN"1"3;
%"P3V3_STBY"
"1","(-5775,3600)","0","mstr_symbols","I6";
;
SIZE"1B"
VOLTAGE"3.3V"
CDS_LIB"mstr_symbols"
BODY_TYPE"PLUMBING"
HDL_POWER"P3V3_STBY";
"G\NAC"3;
%"GND"
"1","(-6225,2025)","0","mstr_symbols","I7";
;
SIZE"1B"
CDS_LIB"mstr_symbols"
VOLTAGE"0.0V"
BODY_TYPE"PLUMBING"
HDL_POWER"GND";
"A\NAC"4;
%"RES"
"1","(-5725,2750)","0","mstr_discrete","I9";
;
LOCATION"RN8F5"
VALUE"33.2"
CDS_LOCATION"RN8F5"
SEC"1"
SEC_TYPE"0402"
PART_NUMBER"G21796-074"
BOM_COST"SM_MEM"
PACK_TYPE"0402"
MATERIAL"CHIP"
ROOM"BMC_BOOT_SPI"
CDS_LIB"mstr_discrete"
TOLERANCE"1%"
WATTAGE"1/16W"
CDS_SEC"1";
"B"
$PN"2"18;
"A"
$PN"1"14;
END.
